# S9S_MB_2U (Grand Teton) — schematic netlist excerpt (pin names and nets, part order shuffled) for the footprints in the layout excerpt that follows; sources: Cadence DE-HDL packaged netlist, KiCad conversion of 03242023_DA0F0TMBIJ0_F0T_Motherboard_J_brd_V01_OCP.brd

PJ45  Q_SHORT  EMPTY  pkg SM  page 274 : \1\ = VSENSE_PVCCINFAON_CPU0_DP ; \2\ = SH_PVCCINFAON_CPU0

Q80  MOSFET_NCH_DUAL  PJT138K IC  pkg SOT363XD  page 253
  S1  = GND
  G1  = PWRGD_PVCCFA_EHV_CPU0
  D2  = LED_PWRGD_PVCCFA_EHV_FIVRA_CP_1
  S2  = GND
  G2  = PWRGD_PVCCFA_EHV_FIVRA_CPU0
  D1  = LED_PWRGD_PVCCFA_EHV_CPU0_D

C860  Q_CAP_DIFFBUS  DIFF BUS_0.22UF 6.3V 20% X6S  pkg C0201  page 174 : \1\ = P5E_CPU0_PE1_TX_C_DN<4> ; \2\ = P5E_CPU0_PE1_TX_DN<4>

(kicad_pcb
	(version 20260206)
	(generator "pcbnew")
	(generator_version "10.0")
	(general
		(thickness 1.6)
		(legacy_teardrops no)
	)
	(paper "A4")
	(title_block
		(title "03242023_DA0F0TMBIJ0_F0T_Motherboard_J_brd_V01_OCP.brd")
		(comment 1 "Grand Teton / footprints 417-419 of 6105")
	)
	(layers
		(0 "F.Cu" signal "TOP")
		(4 "In1.Cu" signal "GND")
		(6 "In2.Cu" signal "IN1")
		(8 "In3.Cu" signal "GND1")
		(10 "In4.Cu" signal "IN2")
		(12 "In5.Cu" signal "GND2")
		(14 "In6.Cu" signal "IN3")
		(16 "In7.Cu" signal "GND3")
		(18 "In8.Cu" signal "VCC")
		(20 "In9.Cu" signal "VCC1")
		(22 "In10.Cu" signal "GND4")
		(24 "In11.Cu" signal "IN4")
		(26 "In12.Cu" signal "GND5")
		(28 "In13.Cu" signal "IN5")
		(30 "In14.Cu" signal "GND6")
		(32 "In15.Cu" signal "IN6")
		(34 "In16.Cu" signal "GND7")
		(2 "B.Cu" signal "BOTTOM")
		(9 "F.Adhes" user "F.Adhesive")
		(11 "B.Adhes" user "B.Adhesive")
		(13 "F.Paste" user "Package Geometry/Pastemask Top")
		(15 "B.Paste" user "Package Geometry/Pastemask Bottom")
		(5 "F.SilkS" user "Ref Des/Silkscreen Top")
		(7 "B.SilkS" user "Ref Des/Silkscreen Bottom")
		(1 "F.Mask" user "Board Geometry/Soldermask Top")
		(3 "B.Mask" user "Board Geometry/Soldermask Bottom")
		(17 "Dwgs.User" user "User.Drawings")
		(19 "Cmts.User" user "User.Comments")
		(21 "Eco1.User" user "User.Eco1")
		(23 "Eco2.User" user "User.Eco2")
		(25 "Edge.Cuts" user "Board Geometry/Outline")
		(27 "Margin" user)
		(31 "F.CrtYd" user "Package Geometry/Place Bound Top")
		(29 "B.CrtYd" user "Package Geometry/Place Bound Bottom")
		(35 "F.Fab" user "Ref Des/Assembly Top")
		(33 "B.Fab" user "Ref Des/Assembly Bottom")
	)
	(footprint ""
		(layer "F.Cu")
		(at 85.576156 -92.888308)
		(property "Reference" "Q80"
			(at -4.63804 -0.635508 0)
			(unlocked yes)
			(layer "F.SilkS")
			(effects
				(font
					(size 0.7874 0.5842)
					(thickness 0.1524)
				)
				(justify left)
			)
		)
		(property "Value" ""
			(at 0 0 0)
			(layer "F.Fab")
			(effects
				(font
					(size 1.27 1.27)
				)
			)
		)
		(duplicate_pad_numbers_are_jumpers no)
		(fp_line
			(start -1.332738 -1.100074)
			(end -0.4826 -1.100074)
			(stroke
				(width 0.1524)
				(type default)
			)
			(layer "F.SilkS")
		)
		(fp_line
			(start -1.332738 1.100074)
			(end -1.332738 -1.100074)
			(stroke
				(width 0.1524)
				(type default)
			)
			(layer "F.SilkS")
		)
		(fp_line
			(start -0.4826 -1.100074)
			(end 0 -0.541274)
			(stroke
				(width 0.1524)
				(type default)
			)
			(layer "F.SilkS")
		)
		(fp_line
			(start 0 -0.541274)
			(end 0.4826 -1.100074)
			(stroke
				(width 0.1524)
				(type default)
			)
			(layer "F.SilkS")
		)
		(fp_line
			(start 0.4826 -1.100074)
			(end 1.332738 -1.100074)
			(stroke
				(width 0.1524)
				(type default)
			)
			(layer "F.SilkS")
		)
		(fp_line
			(start 1.332738 -1.100074)
			(end 1.332738 1.100074)
			(stroke
				(width 0.1524)
				(type default)
			)
			(layer "F.SilkS")
		)
		(fp_line
			(start 1.332738 1.100074)
			(end -1.332738 1.100074)
			(stroke
				(width 0.1524)
				(type default)
			)
			(layer "F.SilkS")
		)
		(fp_poly
			(pts
				(xy -2.2352 -1.001014) (xy -1.533144 -0.649986) (xy -2.2352 -0.298958)
			)
			(stroke
				(width 0)
				(type default)
			)
			(fill yes)
			(layer "F.SilkS")
		)
		(fp_line
			(start -0.674878 -1.100074)
			(end 0.674878 -1.100074)
			(stroke
				(width 0.1)
				(type default)
			)
			(layer "F.Fab")
		)
		(fp_line
			(start -0.674878 1.100074)
			(end -0.674878 -1.100074)
			(stroke
				(width 0.1)
				(type default)
			)
			(layer "F.Fab")
		)
		(fp_line
			(start 0.674878 -1.100074)
			(end 0.674878 1.100074)
			(stroke
				(width 0.1)
				(type default)
			)
			(layer "F.Fab")
		)
		(fp_line
			(start 0.674878 1.100074)
			(end -0.674878 1.100074)
			(stroke
				(width 0.1)
				(type default)
			)
			(layer "F.Fab")
		)
		(fp_poly
			(pts
				(xy -2.2352 -0.298958) (xy -2.2352 -1.001014) (xy -1.533144 -0.649986)
			)
			(stroke
				(width 0)
				(type default)
			)
			(fill yes)
			(layer "F.Fab")
		)
		(pad "1" smd rect
			(at -0.94996 -0.649986 90)
			(size 0.4318 0.508)
			(layers "F.Cu" "F.Mask" "F.Paste")
			(net "GND")
		)
		(pad "2" smd rect
			(at -0.94996 0 90)
			(size 0.4318 0.508)
			(layers "F.Cu" "F.Mask" "F.Paste")
			(net "PWRGD_PVCCFA_EHV_CPU0")
		)
		(pad "3" smd rect
			(at -0.94996 0.649986 90)
			(size 0.4318 0.508)
			(layers "F.Cu" "F.Mask" "F.Paste")
			(net "LED_PWRGD_PVCCFA_EHV_FIVRA_CP_1")
		)
		(pad "4" smd rect
			(at 0.94996 0.649986 90)
			(size 0.4318 0.508)
			(layers "F.Cu" "F.Mask" "F.Paste")
			(net "GND")
		)
		(pad "5" smd rect
			(at 0.94996 0 90)
			(size 0.4318 0.508)
			(layers "F.Cu" "F.Mask" "F.Paste")
			(net "PWRGD_PVCCFA_EHV_FIVRA_CPU0")
		)
		(pad "6" smd rect
			(at 0.94996 -0.649986 90)
			(size 0.4318 0.508)
			(layers "F.Cu" "F.Mask" "F.Paste")
			(net "LED_PWRGD_PVCCFA_EHV_CPU0_D")
		)
	)
	(footprint ""
		(layer "F.Cu")
		(at 421.0558 -17.612614 90)
		(property "Reference" "C860"
			(at 0 0 90)
			(layer "F.SilkS")
			(hide yes)
			(effects
				(font
					(size 1.27 1.27)
				)
			)
		)
		(property "Value" ""
			(at 0 0 90)
			(layer "F.Fab")
			(effects
				(font
					(size 1.27 1.27)
				)
			)
		)
		(duplicate_pad_numbers_are_jumpers no)
		(fp_line
			(start 0.299974 -0.150114)
			(end 0.299974 0.150114)
			(stroke
				(width 0.1)
				(type default)
			)
			(layer "F.Fab")
		)
		(fp_line
			(start -0.299974 -0.150114)
			(end 0.299974 -0.150114)
			(stroke
				(width 0.1)
				(type default)
			)
			(layer "F.Fab")
		)
		(fp_line
			(start 0.299974 0.150114)
			(end -0.299974 0.150114)
			(stroke
				(width 0.1)
				(type default)
			)
			(layer "F.Fab")
		)
		(fp_line
			(start -0.299974 0.150114)
			(end -0.299974 -0.150114)
			(stroke
				(width 0.1)
				(type default)
			)
			(layer "F.Fab")
		)
		(pad "1" smd rect
			(at -0.2667 0 90)
			(size 0.3048 0.381)
			(layers "F.Cu" "F.Mask" "F.Paste")
			(net "P5E_CPU0_PE1_TX_C_DN<4>")
		)
		(pad "2" smd rect
			(at 0.2667 0 90)
			(size 0.3048 0.381)
			(layers "F.Cu" "F.Mask" "F.Paste")
			(net "P5E_CPU0_PE1_TX_DN<4>")
		)
	)
	(footprint ""
		(layer "F.Cu")
		(at 429.267112 -143.1671 -90)
		(property "Reference" "PJ45"
			(at -1.386078 -1.278128 0)
			(unlocked yes)
			(layer "F.SilkS")
			(effects
				(font
					(size 0.7874 0.5842)
					(thickness 0.1524)
				)
				(justify left)
			)
		)
		(property "Value" ""
			(at 0 0 270)
			(layer "F.Fab")
			(effects
				(font
					(size 1.27 1.27)
				)
			)
		)
		(duplicate_pad_numbers_are_jumpers no)
		(pad "1" smd circle
			(at -0.7493 0)
			(size 0 0)
			(layers "F.Cu" "F.Mask" "F.Paste")
			(net "VSENSE_PVCCINFAON_CPU0_DP")
		)
		(pad "2" smd rect
			(at 0.7493 0 180)
			(size 0.7112 0.8128)
			(layers "F.Cu" "F.Mask" "F.Paste")
			(net "SH_PVCCINFAON_CPU0")
		)
		(zone
			(layer "F.Cu")
			(hatch none 0.5)
			(connect_pads
				(clearance 0)
			)
			(min_thickness 0.25)
			(keepout
				(tracks allowed)
				(vias not_allowed)
				(pads allowed)
				(copperpour not_allowed)
				(footprints allowed)
			)
			(placement
				(enabled no)
				(sheetname "")
			)
			(fill
				(thermal_gap 0.5)
				(thermal_bridge_width 0.5)
				(island_removal_mode 0)
			)
			(polygon
				(pts
					(xy 428.855886 -141.9606) (xy 429.673512 -141.9606) (xy 429.673512 -144.3482) (xy 428.855886 -144.3482)
				)
			)
		)
	)
)
